(kicad_pcb
	(version 20260206)
	(generator "pcbnew")
	(generator_version "10.0")
	(general
		(thickness 1.6)
		(legacy_teardrops no)
	)
	(paper "A4")
	(title_block
		(title "04192023_DAF0TMB3IC0_F0TG_MB_C_brd_V02_OCP.brd")
		(comment 1 "Grand Teton / footprints 4631-4637 of 8354")
	)
	(layers
		(0 "F.Cu" signal "TOP")
		(4 "In1.Cu" signal "GND")
		(6 "In2.Cu" signal "IN1")
		(8 "In3.Cu" signal "GND1")
		(10 "In4.Cu" signal "IN2")
		(12 "In5.Cu" signal "GND2")
		(14 "In6.Cu" signal "IN3")
		(16 "In7.Cu" signal "GND3")
		(18 "In8.Cu" signal "VCC")
		(20 "In9.Cu" signal "VCC1")
		(22 "In10.Cu" signal "GND4")
		(24 "In11.Cu" signal "IN4")
		(26 "In12.Cu" signal "GND5")
		(28 "In13.Cu" signal "IN5")
		(30 "In14.Cu" signal "GND6")
		(32 "In15.Cu" signal "IN6")
		(34 "In16.Cu" signal "GND7")
		(2 "B.Cu" signal "BOTTOM")
		(9 "F.Adhes" user "F.Adhesive")
		(11 "B.Adhes" user "B.Adhesive")
		(13 "F.Paste" user "Package Geometry/Pastemask Top")
		(15 "B.Paste" user "Package Geometry/Pastemask Bottom")
		(5 "F.SilkS" user "Ref Des/Silkscreen Top")
		(7 "B.SilkS" user "Ref Des/Silkscreen Bottom")
		(1 "F.Mask" user "Board Geometry/Soldermask Top")
		(3 "B.Mask" user "Board Geometry/Soldermask Bottom")
		(17 "Dwgs.User" user "User.Drawings")
		(19 "Cmts.User" user "User.Comments")
		(21 "Eco1.User" user "User.Eco1")
		(23 "Eco2.User" user "User.Eco2")
		(25 "Edge.Cuts" user "Board Geometry/Outline")
		(27 "Margin" user)
		(31 "F.CrtYd" user "Package Geometry/Place Bound Top")
		(29 "B.CrtYd" user "Package Geometry/Place Bound Bottom")
		(35 "F.Fab" user "Ref Des/Assembly Top")
		(33 "B.Fab" user "Ref Des/Assembly Bottom")
	)
	(footprint ""
		(layer "F.Cu")
		(at 171.196 -121.376948)
		(property "Reference" "R6029"
			(at 0 0 0)
			(layer "F.SilkS")
			(hide yes)
			(effects
				(font
					(size 1.27 1.27)
				)
			)
		)
		(property "Value" ""
			(at 0 0 0)
			(layer "F.Fab")
			(effects
				(font
					(size 1.27 1.27)
				)
			)
		)
		(duplicate_pad_numbers_are_jumpers no)
		(fp_line
			(start -0.7874 -0.4064)
			(end 0.7874 -0.4064)
			(stroke
				(width 0.1524)
				(type default)
			)
			(layer "F.SilkS")
		)
		(fp_line
			(start -0.7874 0.4064)
			(end -0.7874 -0.4064)
			(stroke
				(width 0.1524)
				(type default)
			)
			(layer "F.SilkS")
		)
		(fp_line
			(start 0.7874 -0.4064)
			(end 0.7874 0.4064)
			(stroke
				(width 0.1524)
				(type default)
			)
			(layer "F.SilkS")
		)
		(fp_line
			(start 0.7874 0.4064)
			(end -0.7874 0.4064)
			(stroke
				(width 0.1524)
				(type default)
			)
			(layer "F.SilkS")
		)
		(fp_line
			(start -0.67945 -0.305054)
			(end -0.12065 -0.305054)
			(stroke
				(width 0.1)
				(type default)
			)
			(layer "F.Fab")
		)
		(fp_line
			(start -0.67945 0.3048)
			(end -0.67945 -0.305054)
			(stroke
				(width 0.1)
				(type default)
			)
			(layer "F.Fab")
		)
		(fp_line
			(start -0.12065 -0.305054)
			(end -0.12065 -0.2794)
			(stroke
				(width 0.1)
				(type default)
			)
			(layer "F.Fab")
		)
		(fp_line
			(start -0.12065 -0.2794)
			(end 0.12065 -0.2794)
			(stroke
				(width 0.1)
				(type default)
			)
			(layer "F.Fab")
		)
		(fp_line
			(start -0.12065 0.2794)
			(end -0.12065 0.3048)
			(stroke
				(width 0.1)
				(type default)
			)
			(layer "F.Fab")
		)
		(fp_line
			(start -0.12065 0.3048)
			(end -0.67945 0.3048)
			(stroke
				(width 0.1)
				(type default)
			)
			(layer "F.Fab")
		)
		(fp_line
			(start 0.120396 0.2794)
			(end -0.12065 0.2794)
			(stroke
				(width 0.1)
				(type default)
			)
			(layer "F.Fab")
		)
		(fp_line
			(start 0.120396 0.3048)
			(end 0.120396 0.2794)
			(stroke
				(width 0.1)
				(type default)
			)
			(layer "F.Fab")
		)
		(fp_line
			(start 0.12065 -0.3048)
			(end 0.67945 -0.3048)
			(stroke
				(width 0.1)
				(type default)
			)
			(layer "F.Fab")
		)
		(fp_line
			(start 0.12065 -0.2794)
			(end 0.12065 -0.3048)
			(stroke
				(width 0.1)
				(type default)
			)
			(layer "F.Fab")
		)
		(fp_line
			(start 0.67945 -0.3048)
			(end 0.67945 0.3048)
			(stroke
				(width 0.1)
				(type default)
			)
			(layer "F.Fab")
		)
		(fp_line
			(start 0.67945 0.3048)
			(end 0.120396 0.3048)
			(stroke
				(width 0.1)
				(type default)
			)
			(layer "F.Fab")
		)
		(pad "1" smd circle
			(at -0.40005 0)
			(size 0 0)
			(layers "F.Cu" "F.Mask" "F.Paste")
			(net "CLK_GEN2_BMC_RC_OE_N")
		)
		(pad "2" smd circle
			(at 0.40005 0)
			(size 0 0)
			(layers "F.Cu" "F.Mask" "F.Paste")
			(net "CLK_GEN2_BMC_RC_OE_R_N")
		)
	)
	(footprint ""
		(layer "F.Cu")
		(at 148.564346 -408.517344 -90)
		(property "Reference" "C6716"
			(at 0 0 270)
			(layer "F.SilkS")
			(hide yes)
			(effects
				(font
					(size 1.27 1.27)
				)
			)
		)
		(property "Value" ""
			(at 0 0 270)
			(layer "F.Fab")
			(effects
				(font
					(size 1.27 1.27)
				)
			)
		)
		(duplicate_pad_numbers_are_jumpers no)
		(fp_line
			(start -0.299974 0.150114)
			(end -0.299974 -0.150114)
			(stroke
				(width 0.1)
				(type default)
			)
			(layer "F.Fab")
		)
		(fp_line
			(start 0.299974 0.150114)
			(end -0.299974 0.150114)
			(stroke
				(width 0.1)
				(type default)
			)
			(layer "F.Fab")
		)
		(fp_line
			(start -0.299974 -0.150114)
			(end 0.299974 -0.150114)
			(stroke
				(width 0.1)
				(type default)
			)
			(layer "F.Fab")
		)
		(fp_line
			(start 0.299974 -0.150114)
			(end 0.299974 0.150114)
			(stroke
				(width 0.1)
				(type default)
			)
			(layer "F.Fab")
		)
		(pad "1" smd rect
			(at -0.2667 0 270)
			(size 0.3048 0.381)
			(layers "F.Cu" "F.Mask" "F.Paste")
			(net "P5E_CPU1_P2_TX_BUF_C_DN<11>")
		)
		(pad "2" smd rect
			(at 0.2667 0 270)
			(size 0.3048 0.381)
			(layers "F.Cu" "F.Mask" "F.Paste")
			(net "P5E_CPU1_P2_TX_BUF_DN<11>")
		)
	)
	(footprint ""
		(layer "F.Cu")
		(at 266.726416 -422.626536 -90)
		(property "Reference" "R1526"
			(at 0 0 270)
			(layer "F.SilkS")
			(hide yes)
			(effects
				(font
					(size 1.27 1.27)
				)
			)
		)
		(property "Value" ""
			(at 0 0 270)
			(layer "F.Fab")
			(effects
				(font
					(size 1.27 1.27)
				)
			)
		)
		(duplicate_pad_numbers_are_jumpers no)
		(fp_line
			(start -0.7874 0.4064)
			(end -0.7874 -0.4064)
			(stroke
				(width 0.1524)
				(type default)
			)
			(layer "F.SilkS")
		)
		(fp_line
			(start 0.7874 0.4064)
			(end -0.7874 0.4064)
			(stroke
				(width 0.1524)
				(type default)
			)
			(layer "F.SilkS")
		)
		(fp_line
			(start -0.7874 -0.4064)
			(end 0.7874 -0.4064)
			(stroke
				(width 0.1524)
				(type default)
			)
			(layer "F.SilkS")
		)
		(fp_line
			(start 0.7874 -0.4064)
			(end 0.7874 0.4064)
			(stroke
				(width 0.1524)
				(type default)
			)
			(layer "F.SilkS")
		)
		(fp_line
			(start -0.67945 0.3048)
			(end -0.67945 -0.305054)
			(stroke
				(width 0.1)
				(type default)
			)
			(layer "F.Fab")
		)
		(fp_line
			(start -0.12065 0.3048)
			(end -0.67945 0.3048)
			(stroke
				(width 0.1)
				(type default)
			)
			(layer "F.Fab")
		)
		(fp_line
			(start 0.120396 0.3048)
			(end 0.120396 0.2794)
			(stroke
				(width 0.1)
				(type default)
			)
			(layer "F.Fab")
		)
		(fp_line
			(start 0.67945 0.3048)
			(end 0.120396 0.3048)
			(stroke
				(width 0.1)
				(type default)
			)
			(layer "F.Fab")
		)
		(fp_line
			(start -0.12065 0.2794)
			(end -0.12065 0.3048)
			(stroke
				(width 0.1)
				(type default)
			)
			(layer "F.Fab")
		)
		(fp_line
			(start 0.120396 0.2794)
			(end -0.12065 0.2794)
			(stroke
				(width 0.1)
				(type default)
			)
			(layer "F.Fab")
		)
		(fp_line
			(start -0.12065 -0.2794)
			(end 0.12065 -0.2794)
			(stroke
				(width 0.1)
				(type default)
			)
			(layer "F.Fab")
		)
		(fp_line
			(start 0.12065 -0.2794)
			(end 0.12065 -0.3048)
			(stroke
				(width 0.1)
				(type default)
			)
			(layer "F.Fab")
		)
		(fp_line
			(start 0.12065 -0.3048)
			(end 0.67945 -0.3048)
			(stroke
				(width 0.1)
				(type default)
			)
			(layer "F.Fab")
		)
		(fp_line
			(start 0.67945 -0.3048)
			(end 0.67945 0.3048)
			(stroke
				(width 0.1)
				(type default)
			)
			(layer "F.Fab")
		)
		(fp_line
			(start -0.67945 -0.305054)
			(end -0.12065 -0.305054)
			(stroke
				(width 0.1)
				(type default)
			)
			(layer "F.Fab")
		)
		(fp_line
			(start -0.12065 -0.305054)
			(end -0.12065 -0.2794)
			(stroke
				(width 0.1)
				(type default)
			)
			(layer "F.Fab")
		)
		(pad "1" smd circle
			(at -0.40005 0 270)
			(size 0 0)
			(layers "F.Cu" "F.Mask" "F.Paste")
			(net "PDB_PRSNT_N")
		)
		(pad "2" smd circle
			(at 0.40005 0 270)
			(size 0 0)
			(layers "F.Cu" "F.Mask" "F.Paste")
			(net "PDB_PRSNT_R_N")
		)
	)
	(footprint ""
		(layer "F.Cu")
		(at 208.878932 -117.748812)
		(property "Reference" "R3481"
			(at 0 0 0)
			(layer "F.SilkS")
			(hide yes)
			(effects
				(font
					(size 1.27 1.27)
				)
			)
		)
		(property "Value" ""
			(at 0 0 0)
			(layer "F.Fab")
			(effects
				(font
					(size 1.27 1.27)
				)
			)
		)
		(duplicate_pad_numbers_are_jumpers no)
		(fp_line
			(start -0.7874 -0.4064)
			(end 0.7874 -0.4064)
			(stroke
				(width 0.1524)
				(type default)
			)
			(layer "F.SilkS")
		)
		(fp_line
			(start -0.7874 0.4064)
			(end -0.7874 -0.4064)
			(stroke
				(width 0.1524)
				(type default)
			)
			(layer "F.SilkS")
		)
		(fp_line
			(start 0.7874 -0.4064)
			(end 0.7874 0.4064)
			(stroke
				(width 0.1524)
				(type default)
			)
			(layer "F.SilkS")
		)
		(fp_line
			(start 0.7874 0.4064)
			(end -0.7874 0.4064)
			(stroke
				(width 0.1524)
				(type default)
			)
			(layer "F.SilkS")
		)
		(fp_line
			(start -0.67945 -0.305054)
			(end -0.12065 -0.305054)
			(stroke
				(width 0.1)
				(type default)
			)
			(layer "F.Fab")
		)
		(fp_line
			(start -0.67945 0.3048)
			(end -0.67945 -0.305054)
			(stroke
				(width 0.1)
				(type default)
			)
			(layer "F.Fab")
		)
		(fp_line
			(start -0.12065 -0.305054)
			(end -0.12065 -0.2794)
			(stroke
				(width 0.1)
				(type default)
			)
			(layer "F.Fab")
		)
		(fp_line
			(start -0.12065 -0.2794)
			(end 0.12065 -0.2794)
			(stroke
				(width 0.1)
				(type default)
			)
			(layer "F.Fab")
		)
		(fp_line
			(start -0.12065 0.2794)
			(end -0.12065 0.3048)
			(stroke
				(width 0.1)
				(type default)
			)
			(layer "F.Fab")
		)
		(fp_line
			(start -0.12065 0.3048)
			(end -0.67945 0.3048)
			(stroke
				(width 0.1)
				(type default)
			)
			(layer "F.Fab")
		)
		(fp_line
			(start 0.120396 0.2794)
			(end -0.12065 0.2794)
			(stroke
				(width 0.1)
				(type default)
			)
			(layer "F.Fab")
		)
		(fp_line
			(start 0.120396 0.3048)
			(end 0.120396 0.2794)
			(stroke
				(width 0.1)
				(type default)
			)
			(layer "F.Fab")
		)
		(fp_line
			(start 0.12065 -0.3048)
			(end 0.67945 -0.3048)
			(stroke
				(width 0.1)
				(type default)
			)
			(layer "F.Fab")
		)
		(fp_line
			(start 0.12065 -0.2794)
			(end 0.12065 -0.3048)
			(stroke
				(width 0.1)
				(type default)
			)
			(layer "F.Fab")
		)
		(fp_line
			(start 0.67945 -0.3048)
			(end 0.67945 0.3048)
			(stroke
				(width 0.1)
				(type default)
			)
			(layer "F.Fab")
		)
		(fp_line
			(start 0.67945 0.3048)
			(end 0.120396 0.3048)
			(stroke
				(width 0.1)
				(type default)
			)
			(layer "F.Fab")
		)
		(pad "1" smd circle
			(at -0.40005 0)
			(size 0 0)
			(layers "F.Cu" "F.Mask" "F.Paste")
			(net "GPU_HMC_PRSNT_ISO_R_N")
		)
		(pad "2" smd circle
			(at 0.40005 0)
			(size 0 0)
			(layers "F.Cu" "F.Mask" "F.Paste")
			(net "GPU_HMC_PRSNT_ISO_N")
		)
	)
	(footprint ""
		(layer "F.Cu")
		(at 136.311386 -408.517344 -90)
		(property "Reference" "C6708"
			(at 0 0 270)
			(layer "F.SilkS")
			(hide yes)
			(effects
				(font
					(size 1.27 1.27)
				)
			)
		)
		(property "Value" ""
			(at 0 0 270)
			(layer "F.Fab")
			(effects
				(font
					(size 1.27 1.27)
				)
			)
		)
		(duplicate_pad_numbers_are_jumpers no)
		(fp_line
			(start -0.299974 0.150114)
			(end -0.299974 -0.150114)
			(stroke
				(width 0.1)
				(type default)
			)
			(layer "F.Fab")
		)
		(fp_line
			(start 0.299974 0.150114)
			(end -0.299974 0.150114)
			(stroke
				(width 0.1)
				(type default)
			)
			(layer "F.Fab")
		)
		(fp_line
			(start -0.299974 -0.150114)
			(end 0.299974 -0.150114)
			(stroke
				(width 0.1)
				(type default)
			)
			(layer "F.Fab")
		)
		(fp_line
			(start 0.299974 -0.150114)
			(end 0.299974 0.150114)
			(stroke
				(width 0.1)
				(type default)
			)
			(layer "F.Fab")
		)
		(pad "1" smd rect
			(at -0.2667 0 270)
			(size 0.3048 0.381)
			(layers "F.Cu" "F.Mask" "F.Paste")
			(net "P5E_CPU1_P2_TX_BUF_C_DN<7>")
		)
		(pad "2" smd rect
			(at 0.2667 0 270)
			(size 0.3048 0.381)
			(layers "F.Cu" "F.Mask" "F.Paste")
			(net "P5E_CPU1_P2_TX_BUF_DN<7>")
		)
	)
	(footprint ""
		(layer "F.Cu")
		(at 70.739 -54.61 180)
		(property "Reference" "R1146"
			(at 0 0 180)
			(layer "F.SilkS")
			(hide yes)
			(effects
				(font
					(size 1.27 1.27)
				)
			)
		)
		(property "Value" ""
			(at 0 0 180)
			(layer "F.Fab")
			(effects
				(font
					(size 1.27 1.27)
				)
			)
		)
		(duplicate_pad_numbers_are_jumpers no)
		(fp_line
			(start 0.7874 0.4064)
			(end -0.7874 0.4064)
			(stroke
				(width 0.1524)
				(type default)
			)
			(layer "F.SilkS")
		)
		(fp_line
			(start 0.7874 -0.4064)
			(end 0.7874 0.4064)
			(stroke
				(width 0.1524)
				(type default)
			)
			(layer "F.SilkS")
		)
		(fp_line
			(start -0.7874 0.4064)
			(end -0.7874 -0.4064)
			(stroke
				(width 0.1524)
				(type default)
			)
			(layer "F.SilkS")
		)
		(fp_line
			(start -0.7874 -0.4064)
			(end 0.7874 -0.4064)
			(stroke
				(width 0.1524)
				(type default)
			)
			(layer "F.SilkS")
		)
		(fp_line
			(start 0.67945 0.3048)
			(end 0.120396 0.3048)
			(stroke
				(width 0.1)
				(type default)
			)
			(layer "F.Fab")
		)
		(fp_line
			(start 0.67945 -0.3048)
			(end 0.67945 0.3048)
			(stroke
				(width 0.1)
				(type default)
			)
			(layer "F.Fab")
		)
		(fp_line
			(start 0.12065 -0.2794)
			(end 0.12065 -0.3048)
			(stroke
				(width 0.1)
				(type default)
			)
			(layer "F.Fab")
		)
		(fp_line
			(start 0.12065 -0.3048)
			(end 0.67945 -0.3048)
			(stroke
				(width 0.1)
				(type default)
			)
			(layer "F.Fab")
		)
		(fp_line
			(start 0.120396 0.3048)
			(end 0.120396 0.2794)
			(stroke
				(width 0.1)
				(type default)
			)
			(layer "F.Fab")
		)
		(fp_line
			(start 0.120396 0.2794)
			(end -0.12065 0.2794)
			(stroke
				(width 0.1)
				(type default)
			)
			(layer "F.Fab")
		)
		(fp_line
			(start -0.12065 0.3048)
			(end -0.67945 0.3048)
			(stroke
				(width 0.1)
				(type default)
			)
			(layer "F.Fab")
		)
		(fp_line
			(start -0.12065 0.2794)
			(end -0.12065 0.3048)
			(stroke
				(width 0.1)
				(type default)
			)
			(layer "F.Fab")
		)
		(fp_line
			(start -0.12065 -0.2794)
			(end 0.12065 -0.2794)
			(stroke
				(width 0.1)
				(type default)
			)
			(layer "F.Fab")
		)
		(fp_line
			(start -0.12065 -0.305054)
			(end -0.12065 -0.2794)
			(stroke
				(width 0.1)
				(type default)
			)
			(layer "F.Fab")
		)
		(fp_line
			(start -0.67945 0.3048)
			(end -0.67945 -0.305054)
			(stroke
				(width 0.1)
				(type default)
			)
			(layer "F.Fab")
		)
		(fp_line
			(start -0.67945 -0.305054)
			(end -0.12065 -0.305054)
			(stroke
				(width 0.1)
				(type default)
			)
			(layer "F.Fab")
		)
		(pad "1" smd circle
			(at -0.40005 0 180)
			(size 0 0)
			(layers "F.Cu" "F.Mask" "F.Paste")
			(net "OCP_V3_2_AUX_PWR_EN_R2")
		)
		(pad "2" smd circle
			(at 0.40005 0 180)
			(size 0 0)
			(layers "F.Cu" "F.Mask" "F.Paste")
			(net "HP_LVC3_OCP_V3_2_PWRGD_R1")
		)
	)
	(footprint ""
		(layer "F.Cu")
		(at 171.577 -100.294948 -90)
		(property "Reference" "R6011"
			(at 0 0 270)
			(layer "F.SilkS")
			(hide yes)
			(effects
				(font
					(size 1.27 1.27)
				)
			)
		)
		(property "Value" ""
			(at 0 0 270)
			(layer "F.Fab")
			(effects
				(font
					(size 1.27 1.27)
				)
			)
		)
		(duplicate_pad_numbers_are_jumpers no)
		(fp_line
			(start -0.7874 0.4064)
			(end -0.7874 -0.4064)
			(stroke
				(width 0.1524)
				(type default)
			)
			(layer "F.SilkS")
		)
		(fp_line
			(start 0.7874 0.4064)
			(end -0.7874 0.4064)
			(stroke
				(width 0.1524)
				(type default)
			)
			(layer "F.SilkS")
		)
		(fp_line
			(start -0.7874 -0.4064)
			(end 0.7874 -0.4064)
			(stroke
				(width 0.1524)
				(type default)
			)
			(layer "F.SilkS")
		)
		(fp_line
			(start 0.7874 -0.4064)
			(end 0.7874 0.4064)
			(stroke
				(width 0.1524)
				(type default)
			)
			(layer "F.SilkS")
		)
		(fp_line
			(start -0.67945 0.3048)
			(end -0.67945 -0.305054)
			(stroke
				(width 0.1)
				(type default)
			)
			(layer "F.Fab")
		)
		(fp_line
			(start -0.12065 0.3048)
			(end -0.67945 0.3048)
			(stroke
				(width 0.1)
				(type default)
			)
			(layer "F.Fab")
		)
		(fp_line
			(start 0.120396 0.3048)
			(end 0.120396 0.2794)
			(stroke
				(width 0.1)
				(type default)
			)
			(layer "F.Fab")
		)
		(fp_line
			(start 0.67945 0.3048)
			(end 0.120396 0.3048)
			(stroke
				(width 0.1)
				(type default)
			)
			(layer "F.Fab")
		)
		(fp_line
			(start -0.12065 0.2794)
			(end -0.12065 0.3048)
			(stroke
				(width 0.1)
				(type default)
			)
			(layer "F.Fab")
		)
		(fp_line
			(start 0.120396 0.2794)
			(end -0.12065 0.2794)
			(stroke
				(width 0.1)
				(type default)
			)
			(layer "F.Fab")
		)
		(fp_line
			(start -0.12065 -0.2794)
			(end 0.12065 -0.2794)
			(stroke
				(width 0.1)
				(type default)
			)
			(layer "F.Fab")
		)
		(fp_line
			(start 0.12065 -0.2794)
			(end 0.12065 -0.3048)
			(stroke
				(width 0.1)
				(type default)
			)
			(layer "F.Fab")
		)
		(fp_line
			(start 0.12065 -0.3048)
			(end 0.67945 -0.3048)
			(stroke
				(width 0.1)
				(type default)
			)
			(layer "F.Fab")
		)
		(fp_line
			(start 0.67945 -0.3048)
			(end 0.67945 0.3048)
			(stroke
				(width 0.1)
				(type default)
			)
			(layer "F.Fab")
		)
		(fp_line
			(start -0.67945 -0.305054)
			(end -0.12065 -0.305054)
			(stroke
				(width 0.1)
				(type default)
			)
			(layer "F.Fab")
		)
		(fp_line
			(start -0.12065 -0.305054)
			(end -0.12065 -0.2794)
			(stroke
				(width 0.1)
				(type default)
			)
			(layer "F.Fab")
		)
		(pad "1" smd circle
			(at -0.40005 0 270)
			(size 0 0)
			(layers "F.Cu" "F.Mask" "F.Paste")
			(net "SGPIO_SCM_LD_<0>")
		)
		(pad "2" smd circle
			(at 0.40005 0 270)
			(size 0 0)
			(layers "F.Cu" "F.Mask" "F.Paste")
			(net "SGPIO_SCM_LD_R_<0>")
		)
	)
)
